(kicad_pcb
	(version 20260206)
	(generator "pcbnew")
	(generator_version "10.0")
	(general
		(thickness 1.6)
		(legacy_teardrops no)
	)
	(paper "A4")
	(title_block
		(title "01162023_DA0F0TEBIF0_F0T_Expander_BD_F_brd_V02_OCP.brd")
		(comment 1 "Grand Teton / footprints 9129-9136 of 9728")
	)
	(layers
		(0 "F.Cu" signal "TOP")
		(4 "In1.Cu" signal "GND")
		(6 "In2.Cu" signal "VCC")
		(8 "In3.Cu" signal "VCC1")
		(10 "In4.Cu" signal "GND1")
		(12 "In5.Cu" signal "IN1")
		(14 "In6.Cu" signal "GND2")
		(16 "In7.Cu" signal "IN2")
		(18 "In8.Cu" signal "GND3")
		(20 "In9.Cu" signal "IN3")
		(22 "In10.Cu" signal "GND4")
		(24 "In11.Cu" signal "IN4")
		(26 "In12.Cu" signal "GND5")
		(28 "In13.Cu" signal "IN5")
		(30 "In14.Cu" signal "GND6")
		(32 "In15.Cu" signal "IN6")
		(34 "In16.Cu" signal "GND7")
		(2 "B.Cu" signal "BOTTOM")
		(9 "F.Adhes" user "F.Adhesive")
		(11 "B.Adhes" user "B.Adhesive")
		(13 "F.Paste" user "Package Geometry/Pastemask Top")
		(15 "B.Paste" user "Package Geometry/Pastemask Bottom")
		(5 "F.SilkS" user "Ref Des/Silkscreen Top")
		(7 "B.SilkS" user "Ref Des/Silkscreen Bottom")
		(1 "F.Mask" user "Board Geometry/Soldermask Top")
		(3 "B.Mask" user "Board Geometry/Soldermask Bottom")
		(17 "Dwgs.User" user "User.Drawings")
		(19 "Cmts.User" user "User.Comments")
		(21 "Eco1.User" user "User.Eco1")
		(23 "Eco2.User" user "User.Eco2")
		(25 "Edge.Cuts" user "Board Geometry/Outline")
		(27 "Margin" user)
		(31 "F.CrtYd" user "Package Geometry/Place Bound Top")
		(29 "B.CrtYd" user "Package Geometry/Place Bound Bottom")
		(35 "F.Fab" user "Ref Des/Assembly Top")
		(33 "B.Fab" user "Ref Des/Assembly Bottom")
	)
	(footprint ""
		(layer "B.Cu")
		(at 47.820326 -302.028606)
		(property "Reference" "C2988"
			(at 0 0 0)
			(layer "B.SilkS")
			(hide yes)
			(effects
				(font
					(size 1.27 1.27)
				)
				(justify mirror)
			)
		)
		(property "Value" ""
			(at 0 0 0)
			(layer "B.Fab")
			(effects
				(font
					(size 1.27 1.27)
				)
				(justify mirror)
			)
		)
		(duplicate_pad_numbers_are_jumpers no)
		(fp_line
			(start -1.2954 -0.5842)
			(end -1.2954 0.5842)
			(stroke
				(width 0.1524)
				(type default)
			)
			(layer "B.SilkS")
		)
		(fp_line
			(start -1.2954 0.5842)
			(end 1.2954 0.5842)
			(stroke
				(width 0.1524)
				(type default)
			)
			(layer "B.SilkS")
		)
		(fp_line
			(start 1.2954 -0.5842)
			(end -1.2954 -0.5842)
			(stroke
				(width 0.1524)
				(type default)
			)
			(layer "B.SilkS")
		)
		(fp_line
			(start 1.2954 0.5842)
			(end 1.2954 -0.5842)
			(stroke
				(width 0.1524)
				(type default)
			)
			(layer "B.SilkS")
		)
		(fp_line
			(start -1.1938 -0.4064)
			(end -1.1938 0.4064)
			(stroke
				(width 0.1)
				(type default)
			)
			(layer "B.Fab")
		)
		(fp_line
			(start -1.1938 0.4064)
			(end -0.8636 0.4064)
			(stroke
				(width 0.1)
				(type default)
			)
			(layer "B.Fab")
		)
		(fp_line
			(start -0.8636 -0.4572)
			(end -0.8636 -0.4064)
			(stroke
				(width 0.1)
				(type default)
			)
			(layer "B.Fab")
		)
		(fp_line
			(start -0.8636 -0.4064)
			(end -1.1938 -0.4064)
			(stroke
				(width 0.1)
				(type default)
			)
			(layer "B.Fab")
		)
		(fp_line
			(start -0.8636 0.4064)
			(end -0.8636 0.4572)
			(stroke
				(width 0.1)
				(type default)
			)
			(layer "B.Fab")
		)
		(fp_line
			(start -0.8636 0.4572)
			(end 0.8636 0.4572)
			(stroke
				(width 0.1)
				(type default)
			)
			(layer "B.Fab")
		)
		(fp_line
			(start 0.8636 -0.4572)
			(end -0.8636 -0.4572)
			(stroke
				(width 0.1)
				(type default)
			)
			(layer "B.Fab")
		)
		(fp_line
			(start 0.8636 -0.4064)
			(end 0.8636 -0.4572)
			(stroke
				(width 0.1)
				(type default)
			)
			(layer "B.Fab")
		)
		(fp_line
			(start 0.8636 0.4064)
			(end 1.1938 0.4064)
			(stroke
				(width 0.1)
				(type default)
			)
			(layer "B.Fab")
		)
		(fp_line
			(start 0.8636 0.4572)
			(end 0.8636 0.4064)
			(stroke
				(width 0.1)
				(type default)
			)
			(layer "B.Fab")
		)
		(fp_line
			(start 1.1938 -0.4064)
			(end 0.8636 -0.4064)
			(stroke
				(width 0.1)
				(type default)
			)
			(layer "B.Fab")
		)
		(fp_line
			(start 1.1938 0.4064)
			(end 1.1938 -0.4064)
			(stroke
				(width 0.1)
				(type default)
			)
			(layer "B.Fab")
		)
		(pad "1" smd rect
			(at 0.7366 0 270)
			(size 0.7112 0.8128)
			(layers "B.Cu" "B.Mask" "B.Paste")
			(net "P1V8_VDDA_PEX0")
		)
		(pad "2" smd rect
			(at -0.7366 0 270)
			(size 0.7112 0.8128)
			(layers "B.Cu" "B.Mask" "B.Paste")
			(net "GND")
		)
	)
	(footprint ""
		(layer "B.Cu")
		(at 411.750002 -292.099746 90)
		(property "Reference" "C1979"
			(at 0 0 90)
			(layer "B.SilkS")
			(hide yes)
			(effects
				(font
					(size 1.27 1.27)
				)
				(justify mirror)
			)
		)
		(property "Value" ""
			(at 0 0 90)
			(layer "B.Fab")
			(effects
				(font
					(size 1.27 1.27)
				)
				(justify mirror)
			)
		)
		(duplicate_pad_numbers_are_jumpers no)
		(fp_line
			(start 0.299974 -0.150114)
			(end -0.299974 -0.150114)
			(stroke
				(width 0.1)
				(type default)
			)
			(layer "B.Fab")
		)
		(fp_line
			(start -0.299974 -0.150114)
			(end -0.299974 0.150114)
			(stroke
				(width 0.1)
				(type default)
			)
			(layer "B.Fab")
		)
		(fp_line
			(start 0.299974 0.150114)
			(end 0.299974 -0.150114)
			(stroke
				(width 0.1)
				(type default)
			)
			(layer "B.Fab")
		)
		(fp_line
			(start -0.299974 0.150114)
			(end 0.299974 0.150114)
			(stroke
				(width 0.1)
				(type default)
			)
			(layer "B.Fab")
		)
		(pad "1" smd rect
			(at 0.2667 0 270)
			(size 0.3048 0.381)
			(layers "B.Cu" "B.Mask" "B.Paste")
			(net "P0V8_SERDES_VDDA_PEX3")
		)
		(pad "2" smd rect
			(at -0.2667 0 270)
			(size 0.3048 0.381)
			(layers "B.Cu" "B.Mask" "B.Paste")
			(net "GND")
		)
	)
	(footprint ""
		(layer "B.Cu")
		(at 111.229648 -327.856342 90)
		(property "Reference" "R1475"
			(at 0 0 90)
			(layer "B.SilkS")
			(hide yes)
			(effects
				(font
					(size 1.27 1.27)
				)
				(justify mirror)
			)
		)
		(property "Value" ""
			(at 0 0 90)
			(layer "B.Fab")
			(effects
				(font
					(size 1.27 1.27)
				)
				(justify mirror)
			)
		)
		(duplicate_pad_numbers_are_jumpers no)
		(fp_line
			(start 0.7874 -0.4064)
			(end -0.7874 -0.4064)
			(stroke
				(width 0.1524)
				(type default)
			)
			(layer "B.SilkS")
		)
		(fp_line
			(start -0.7874 -0.4064)
			(end -0.7874 0.4064)
			(stroke
				(width 0.1524)
				(type default)
			)
			(layer "B.SilkS")
		)
		(fp_line
			(start 0.7874 0.4064)
			(end 0.7874 -0.4064)
			(stroke
				(width 0.1524)
				(type default)
			)
			(layer "B.SilkS")
		)
		(fp_line
			(start -0.7874 0.4064)
			(end 0.7874 0.4064)
			(stroke
				(width 0.1524)
				(type default)
			)
			(layer "B.SilkS")
		)
		(fp_line
			(start 0.67945 -0.305054)
			(end 0.12065 -0.305054)
			(stroke
				(width 0.1)
				(type default)
			)
			(layer "B.Fab")
		)
		(fp_line
			(start 0.12065 -0.305054)
			(end 0.12065 -0.2794)
			(stroke
				(width 0.1)
				(type default)
			)
			(layer "B.Fab")
		)
		(fp_line
			(start -0.12065 -0.3048)
			(end -0.67945 -0.3048)
			(stroke
				(width 0.1)
				(type default)
			)
			(layer "B.Fab")
		)
		(fp_line
			(start -0.67945 -0.3048)
			(end -0.67945 0.3048)
			(stroke
				(width 0.1)
				(type default)
			)
			(layer "B.Fab")
		)
		(fp_line
			(start 0.12065 -0.2794)
			(end -0.12065 -0.2794)
			(stroke
				(width 0.1)
				(type default)
			)
			(layer "B.Fab")
		)
		(fp_line
			(start -0.12065 -0.2794)
			(end -0.12065 -0.3048)
			(stroke
				(width 0.1)
				(type default)
			)
			(layer "B.Fab")
		)
		(fp_line
			(start 0.12065 0.2794)
			(end 0.12065 0.3048)
			(stroke
				(width 0.1)
				(type default)
			)
			(layer "B.Fab")
		)
		(fp_line
			(start -0.120396 0.2794)
			(end 0.12065 0.2794)
			(stroke
				(width 0.1)
				(type default)
			)
			(layer "B.Fab")
		)
		(fp_line
			(start 0.67945 0.3048)
			(end 0.67945 -0.305054)
			(stroke
				(width 0.1)
				(type default)
			)
			(layer "B.Fab")
		)
		(fp_line
			(start 0.12065 0.3048)
			(end 0.67945 0.3048)
			(stroke
				(width 0.1)
				(type default)
			)
			(layer "B.Fab")
		)
		(fp_line
			(start -0.120396 0.3048)
			(end -0.120396 0.2794)
			(stroke
				(width 0.1)
				(type default)
			)
			(layer "B.Fab")
		)
		(fp_line
			(start -0.67945 0.3048)
			(end -0.120396 0.3048)
			(stroke
				(width 0.1)
				(type default)
			)
			(layer "B.Fab")
		)
		(pad "1" smd circle
			(at 0.40005 0 270)
			(size 0 0)
			(layers "B.Cu" "B.Mask" "B.Paste")
			(net "SMB_BMC_9FGL0451E_SDA")
		)
		(pad "2" smd circle
			(at -0.40005 0 270)
			(size 0 0)
			(layers "B.Cu" "B.Mask" "B.Paste")
			(net "SMB_CLK_ISO_R_SDA")
		)
	)
	(footprint ""
		(layer "B.Cu")
		(at 344.493342 -220.38691 90)
		(property "Reference" "C2065"
			(at 0 0 90)
			(layer "B.SilkS")
			(hide yes)
			(effects
				(font
					(size 1.27 1.27)
				)
				(justify mirror)
			)
		)
		(property "Value" ""
			(at 0 0 90)
			(layer "B.Fab")
			(effects
				(font
					(size 1.27 1.27)
				)
				(justify mirror)
			)
		)
		(duplicate_pad_numbers_are_jumpers no)
		(fp_line
			(start 0.69215 -0.2921)
			(end -0.69215 -0.2921)
			(stroke
				(width 0.1524)
				(type default)
			)
			(layer "B.SilkS")
		)
		(fp_line
			(start -0.69215 -0.2921)
			(end -0.69215 0.2921)
			(stroke
				(width 0.1524)
				(type default)
			)
			(layer "B.SilkS")
		)
		(fp_line
			(start 0.69215 0.2921)
			(end 0.69215 -0.2921)
			(stroke
				(width 0.1524)
				(type default)
			)
			(layer "B.SilkS")
		)
		(fp_line
			(start -0.69215 0.2921)
			(end 0.69215 0.2921)
			(stroke
				(width 0.1524)
				(type default)
			)
			(layer "B.SilkS")
		)
		(fp_line
			(start 0.51435 -0.2794)
			(end -0.51435 -0.2794)
			(stroke
				(width 0.1)
				(type default)
			)
			(layer "B.Fab")
		)
		(fp_line
			(start -0.51435 -0.2794)
			(end -0.51435 0.2794)
			(stroke
				(width 0.1)
				(type default)
			)
			(layer "B.Fab")
		)
		(fp_line
			(start 0.51435 0.2794)
			(end 0.51435 -0.2794)
			(stroke
				(width 0.1)
				(type default)
			)
			(layer "B.Fab")
		)
		(fp_line
			(start -0.51435 0.2794)
			(end 0.51435 0.2794)
			(stroke
				(width 0.1)
				(type default)
			)
			(layer "B.Fab")
		)
		(pad "1" smd circle
			(at 0.40005 0 270)
			(size 0 0)
			(layers "B.Cu" "B.Mask" "B.Paste")
			(net "P3V3_VCC_FPGA_CORE")
		)
		(pad "2" smd circle
			(at -0.40005 0 270)
			(size 0 0)
			(layers "B.Cu" "B.Mask" "B.Paste")
			(net "GND")
		)
		(zone
			(layer "B.Cu")
			(hatch none 0.5)
			(connect_pads
				(clearance 0)
			)
			(min_thickness 0.25)
			(keepout
				(tracks not_allowed)
				(vias allowed)
				(pads allowed)
				(copperpour not_allowed)
				(footprints allowed)
			)
			(placement
				(enabled no)
				(sheetname "")
			)
			(fill
				(thermal_gap 0.5)
				(thermal_bridge_width 0.5)
				(island_removal_mode 0)
			)
			(polygon
				(pts
					(xy 344.580972 -220.57741) (xy 344.639138 -220.48597) (xy 344.639138 -220.28658) (xy 344.580972 -220.19641)
					(xy 344.405712 -220.19641) (xy 344.347292 -220.28658) (xy 344.347292 -220.48597) (xy 344.405458 -220.57741)
				)
			)
		)
	)
	(footprint ""
		(layer "B.Cu")
		(at 353.418902 -222.555816 180)
		(property "Reference" "C2073"
			(at 0 0 0)
			(layer "B.SilkS")
			(hide yes)
			(effects
				(font
					(size 1.27 1.27)
				)
				(justify mirror)
			)
		)
		(property "Value" ""
			(at 0 0 0)
			(layer "B.Fab")
			(effects
				(font
					(size 1.27 1.27)
				)
				(justify mirror)
			)
		)
		(duplicate_pad_numbers_are_jumpers no)
		(fp_line
			(start 0.69215 0.2921)
			(end 0.69215 -0.2921)
			(stroke
				(width 0.1524)
				(type default)
			)
			(layer "B.SilkS")
		)
		(fp_line
			(start 0.69215 -0.2921)
			(end -0.69215 -0.2921)
			(stroke
				(width 0.1524)
				(type default)
			)
			(layer "B.SilkS")
		)
		(fp_line
			(start -0.69215 0.2921)
			(end 0.69215 0.2921)
			(stroke
				(width 0.1524)
				(type default)
			)
			(layer "B.SilkS")
		)
		(fp_line
			(start -0.69215 -0.2921)
			(end -0.69215 0.2921)
			(stroke
				(width 0.1524)
				(type default)
			)
			(layer "B.SilkS")
		)
		(fp_line
			(start 0.51435 0.2794)
			(end 0.51435 -0.2794)
			(stroke
				(width 0.1)
				(type default)
			)
			(layer "B.Fab")
		)
		(fp_line
			(start 0.51435 -0.2794)
			(end -0.51435 -0.2794)
			(stroke
				(width 0.1)
				(type default)
			)
			(layer "B.Fab")
		)
		(fp_line
			(start -0.51435 0.2794)
			(end 0.51435 0.2794)
			(stroke
				(width 0.1)
				(type default)
			)
			(layer "B.Fab")
		)
		(fp_line
			(start -0.51435 -0.2794)
			(end -0.51435 0.2794)
			(stroke
				(width 0.1)
				(type default)
			)
			(layer "B.Fab")
		)
		(pad "1" smd circle
			(at 0.40005 0)
			(size 0 0)
			(layers "B.Cu" "B.Mask" "B.Paste")
			(net "P3V3_VCC_FPGA_CORE")
		)
		(pad "2" smd circle
			(at -0.40005 0)
			(size 0 0)
			(layers "B.Cu" "B.Mask" "B.Paste")
			(net "GND")
		)
		(zone
			(layer "B.Cu")
			(hatch none 0.5)
			(connect_pads
				(clearance 0)
			)
			(min_thickness 0.25)
			(keepout
				(tracks not_allowed)
				(vias allowed)
				(pads allowed)
				(copperpour not_allowed)
				(footprints allowed)
			)
			(placement
				(enabled no)
				(sheetname "")
			)
			(fill
				(thermal_gap 0.5)
				(thermal_bridge_width 0.5)
				(island_removal_mode 0)
			)
			(polygon
				(pts
					(xy 353.228402 -222.643446) (xy 353.319842 -222.701612) (xy 353.519232 -222.701612) (xy 353.609402 -222.643446)
					(xy 353.609402 -222.468186) (xy 353.519232 -222.409766) (xy 353.319842 -222.409766) (xy 353.228402 -222.467932)
				)
			)
		)
	)
	(footprint ""
		(layer "B.Cu")
		(at 219.98432 -290.59632)
		(property "Reference" "PC991"
			(at 0 0 0)
			(layer "B.SilkS")
			(hide yes)
			(effects
				(font
					(size 1.27 1.27)
				)
				(justify mirror)
			)
		)
		(property "Value" ""
			(at 0 0 0)
			(layer "B.Fab")
			(effects
				(font
					(size 1.27 1.27)
				)
				(justify mirror)
			)
		)
		(duplicate_pad_numbers_are_jumpers no)
		(fp_line
			(start -1.524 -0.762)
			(end -1.524 0.762)
			(stroke
				(width 0.1524)
				(type default)
			)
			(layer "B.SilkS")
		)
		(fp_line
			(start -1.524 0.762)
			(end 1.524 0.762)
			(stroke
				(width 0.1524)
				(type default)
			)
			(layer "B.SilkS")
		)
		(fp_line
			(start 1.524 -0.762)
			(end -1.524 -0.762)
			(stroke
				(width 0.1524)
				(type default)
			)
			(layer "B.SilkS")
		)
		(fp_line
			(start 1.524 0.762)
			(end 1.524 -0.762)
			(stroke
				(width 0.1524)
				(type default)
			)
			(layer "B.SilkS")
		)
		(fp_line
			(start -1.1049 -0.724916)
			(end 1.1049 -0.724916)
			(stroke
				(width 0.1)
				(type default)
			)
			(layer "B.Fab")
		)
		(fp_line
			(start -1.1049 0.724916)
			(end -1.1049 -0.724916)
			(stroke
				(width 0.1)
				(type default)
			)
			(layer "B.Fab")
		)
		(fp_line
			(start 1.1049 -0.724916)
			(end 1.1049 0.724916)
			(stroke
				(width 0.1)
				(type default)
			)
			(layer "B.Fab")
		)
		(fp_line
			(start 1.1049 0.724916)
			(end -1.1049 0.724916)
			(stroke
				(width 0.1)
				(type default)
			)
			(layer "B.Fab")
		)
		(pad "1" smd rect
			(at 0.889 0)
			(size 1.016 1.27)
			(layers "B.Cu" "B.Mask" "B.Paste")
			(net "P1V25_PEX1_R")
		)
		(pad "2" smd rect
			(at -0.889 0)
			(size 1.016 1.27)
			(layers "B.Cu" "B.Mask" "B.Paste")
			(net "GND")
		)
	)
	(footprint ""
		(layer "B.Cu")
		(at 400.824954 -286.399732 90)
		(property "Reference" "C3491"
			(at 0 0 90)
			(layer "B.SilkS")
			(hide yes)
			(effects
				(font
					(size 1.27 1.27)
				)
				(justify mirror)
			)
		)
		(property "Value" ""
			(at 0 0 90)
			(layer "B.Fab")
			(effects
				(font
					(size 1.27 1.27)
				)
				(justify mirror)
			)
		)
		(duplicate_pad_numbers_are_jumpers no)
		(fp_line
			(start 0.299974 -0.150114)
			(end -0.299974 -0.150114)
			(stroke
				(width 0.1)
				(type default)
			)
			(layer "B.Fab")
		)
		(fp_line
			(start -0.299974 -0.150114)
			(end -0.299974 0.150114)
			(stroke
				(width 0.1)
				(type default)
			)
			(layer "B.Fab")
		)
		(fp_line
			(start 0.299974 0.150114)
			(end 0.299974 -0.150114)
			(stroke
				(width 0.1)
				(type default)
			)
			(layer "B.Fab")
		)
		(fp_line
			(start -0.299974 0.150114)
			(end 0.299974 0.150114)
			(stroke
				(width 0.1)
				(type default)
			)
			(layer "B.Fab")
		)
		(pad "1" smd rect
			(at 0.2667 0 270)
			(size 0.3048 0.381)
			(layers "B.Cu" "B.Mask" "B.Paste")
			(net "P1V25_SERDES_VDDPLL_PEX3")
		)
		(pad "2" smd rect
			(at -0.2667 0 270)
			(size 0.3048 0.381)
			(layers "B.Cu" "B.Mask" "B.Paste")
			(net "GND")
		)
	)
	(footprint ""
		(layer "B.Cu")
		(at 184.29986 -298.27474 180)
		(property "Reference" "C1372"
			(at 0 0 0)
			(layer "B.SilkS")
			(hide yes)
			(effects
				(font
					(size 1.27 1.27)
				)
				(justify mirror)
			)
		)
		(property "Value" ""
			(at 0 0 0)
			(layer "B.Fab")
			(effects
				(font
					(size 1.27 1.27)
				)
				(justify mirror)
			)
		)
		(duplicate_pad_numbers_are_jumpers no)
		(fp_line
			(start 0.299974 0.150114)
			(end 0.299974 -0.150114)
			(stroke
				(width 0.1)
				(type default)
			)
			(layer "B.Fab")
		)
		(fp_line
			(start 0.299974 -0.150114)
			(end -0.299974 -0.150114)
			(stroke
				(width 0.1)
				(type default)
			)
			(layer "B.Fab")
		)
		(fp_line
			(start -0.299974 0.150114)
			(end 0.299974 0.150114)
			(stroke
				(width 0.1)
				(type default)
			)
			(layer "B.Fab")
		)
		(fp_line
			(start -0.299974 -0.150114)
			(end -0.299974 0.150114)
			(stroke
				(width 0.1)
				(type default)
			)
			(layer "B.Fab")
		)
		(pad "1" smd rect
			(at 0.2667 0)
			(size 0.3048 0.381)
			(layers "B.Cu" "B.Mask" "B.Paste")
			(net "P0V8_PEX1")
		)
		(pad "2" smd rect
			(at -0.2667 0)
			(size 0.3048 0.381)
			(layers "B.Cu" "B.Mask" "B.Paste")
			(net "GND")
		)
	)
)
